(kicad_pcb
	(version 20260206)
	(generator "pcbnew")
	(generator_version "10.0")
	(general
		(thickness 1.6)
		(legacy_teardrops no)
	)
	(paper "A4")
	(title_block
		(title "panther-plus-userver — 13130-1b_20150205.brd")
		(comment 1 "Honey Badger (Wiwynn) / footprint 1214 of 1509 (DIMM3), pads 128-134 of 210")
	)
	(layers
		(0 "F.Cu" signal "TOP")
		(4 "In1.Cu" signal "L2")
		(6 "In2.Cu" signal "L3")
		(8 "In3.Cu" signal "L4")
		(10 "In4.Cu" signal "L5")
		(12 "In5.Cu" signal "L6")
		(14 "In6.Cu" signal "L7")
		(16 "In7.Cu" signal "L8")
		(18 "In8.Cu" signal "L9")
		(20 "In9.Cu" signal "L10")
		(22 "In10.Cu" signal "L11")
		(2 "B.Cu" signal "BOTTOM")
		(9 "F.Adhes" user "F.Adhesive")
		(11 "B.Adhes" user "B.Adhesive")
		(13 "F.Paste" user "Package Geometry/Pastemask Top")
		(15 "B.Paste" user "Package Geometry/Pastemask Bottom")
		(5 "F.SilkS" user "Ref Des/Silkscreen Top")
		(7 "B.SilkS" user "Ref Des/Silkscreen Bottom")
		(1 "F.Mask" user "Board Geometry/Soldermask Top")
		(3 "B.Mask" user "Board Geometry/Soldermask Bottom")
		(17 "Dwgs.User" user "User.Drawings")
		(19 "Cmts.User" user "User.Comments")
		(21 "Eco1.User" user "User.Eco1")
		(23 "Eco2.User" user "User.Eco2")
		(25 "Edge.Cuts" user "Board Geometry/Outline")
		(27 "Margin" user)
		(31 "F.CrtYd" user "Package Geometry/Place Bound Top")
		(29 "B.CrtYd" user "Package Geometry/Place Bound Bottom")
		(35 "F.Fab" user "Ref Des/Assembly Top")
		(33 "B.Fab" user "Ref Des/Assembly Bottom")
	)
	(footprint ""
		(layer "B.Cu")
		(at 159.999934 -5.790692)
		(property "Reference" "DIMM3"
			(at 0 0 0)
			(layer "B.SilkS")
			(hide yes)
			(effects
				(font
					(size 1.27 1.27)
				)
				(justify mirror)
			)
		)
		(property "Value" "DDR3-204P-142-COLAY-1-GP-U"
			(at 41.312338 -16.676878 0)
			(unlocked yes)
			(layer "B.Fab")
			(hide yes)
			(effects
				(font
					(size 1.016 1.016)
					(thickness 0.1524)
				)
				(justify mirror)
			)
		)
		(property "Device Type" "AS0A626-J8R6-7H-COLAY-1"
			(at 41.312338 -18.200878 0)
			(unlocked yes)
			(layer "B.Fab")
			(hide yes)
			(effects
				(font
					(size 1.016 1.016)
					(thickness 0.1524)
				)
				(justify mirror)
			)
		)
		(duplicate_pad_numbers_are_jumpers no)
		(pad "126" smd custom
			(at 8.24992 4.100068 180)
			(size 0.1143 0.1143)
			(layers "B.Cu" "B.Mask" "B.Paste")
			(net "M_B_ODT0")
			(options
				(clearance outline)
				(anchor circle)
			)
			(primitives
				(gr_poly
					(pts
						(xy 0 -0.9017) (xy -0.03175 -0.89916) (xy -0.0635 -0.889) (xy -0.09144 -0.87376) (xy -0.11684 -0.85344)
						(xy -0.13716 -0.82804) (xy -0.1524 -0.8001) (xy -0.16256 -0.76835) (xy -0.1651 -0.7366) (xy -0.1651 0.13462)
						(xy -0.17272 0.14224) (xy -0.19812 0.1778) (xy -0.2032 0.18796) (xy -0.20701 0.19685) (xy -0.21209 0.20701)
						(xy -0.2159 0.21717) (xy -0.21844 0.22733) (xy -0.22225 0.23876) (xy -0.22352 0.24892) (xy -0.22606 0.25908)
						(xy -0.22733 0.27051) (xy -0.22733 0.28067) (xy -0.2286 0.2921) (xy -0.22733 0.30353) (xy -0.22733 0.31369)
						(xy -0.22606 0.32512) (xy -0.22352 0.33528) (xy -0.22225 0.34544) (xy -0.21844 0.35687) (xy -0.2159 0.36703)
						(xy -0.21209 0.37719) (xy -0.20701 0.38735) (xy -0.2032 0.39624) (xy -0.19812 0.4064) (xy -0.17272 0.44196)
						(xy -0.1651 0.44958) (xy -0.1651 0.7366) (xy -0.16256 0.76835) (xy -0.1524 0.8001) (xy -0.13716 0.82804)
						(xy -0.11684 0.85344) (xy -0.09144 0.87376) (xy -0.0635 0.889) (xy -0.03175 0.89916) (xy 0 0.9017)
						(xy 0.03175 0.89916) (xy 0.0635 0.889) (xy 0.09144 0.87376) (xy 0.11684 0.85344) (xy 0.13716 0.82804)
						(xy 0.1524 0.8001) (xy 0.16256 0.76835) (xy 0.1651 0.7366) (xy 0.1651 0.44958) (xy 0.17272 0.44196)
						(xy 0.19812 0.4064) (xy 0.2032 0.39624) (xy 0.20701 0.38735) (xy 0.21209 0.37719) (xy 0.2159 0.36703)
						(xy 0.21844 0.35687) (xy 0.22225 0.34544) (xy 0.22352 0.33528) (xy 0.22606 0.32512) (xy 0.22733 0.31369)
						(xy 0.22733 0.30353) (xy 0.2286 0.2921) (xy 0.22733 0.28067) (xy 0.22733 0.27051) (xy 0.22606 0.25908)
						(xy 0.22352 0.24892) (xy 0.22225 0.23876) (xy 0.21844 0.22733) (xy 0.2159 0.21717) (xy 0.21209 0.20701)
						(xy 0.20701 0.19685) (xy 0.2032 0.18796) (xy 0.19812 0.1778) (xy 0.17272 0.14224) (xy 0.1651 0.13462)
						(xy 0.1651 -0.7366) (xy 0.16256 -0.76835) (xy 0.1524 -0.8001) (xy 0.13716 -0.82804) (xy 0.11684 -0.85344)
						(xy 0.09144 -0.87376) (xy 0.0635 -0.889) (xy 0.03175 -0.89916)
					)
					(width 0)
					(fill yes)
				)
			)
		)
		(pad "127" smd custom
			(at 8.549894 -4.100068 180)
			(size 0.1143 0.1143)
			(layers "B.Cu" "B.Mask" "B.Paste")
			(net "M_B_CS_N0")
			(options
				(clearance outline)
				(anchor circle)
			)
			(primitives
				(gr_poly
					(pts
						(xy 0 -0.9017) (xy -0.03175 -0.89916) (xy -0.0635 -0.889) (xy -0.09144 -0.87376) (xy -0.11684 -0.85344)
						(xy -0.13716 -0.82804) (xy -0.1524 -0.8001) (xy -0.16256 -0.76835) (xy -0.1651 -0.7366) (xy -0.1651 -0.19685)
						(xy -0.17272 -0.18923) (xy -0.17907 -0.18034) (xy -0.18669 -0.17145) (xy -0.19177 -0.16256) (xy -0.19812 -0.15367)
						(xy -0.20828 -0.13335) (xy -0.21971 -0.10287) (xy -0.22225 -0.09271) (xy -0.22479 -0.08128) (xy -0.22606 -0.07112)
						(xy -0.2286 -0.05969) (xy -0.2286 -0.01651) (xy -0.22606 -0.00508) (xy -0.22479 0.00508) (xy -0.22225 0.01651)
						(xy -0.21971 0.02667) (xy -0.20828 0.05715) (xy -0.19812 0.07747) (xy -0.19177 0.08636) (xy -0.18669 0.09525)
						(xy -0.17907 0.10414) (xy -0.17272 0.11303) (xy -0.1651 0.12065) (xy -0.1651 0.7366) (xy -0.16256 0.76835)
						(xy -0.1524 0.8001) (xy -0.13716 0.82804) (xy -0.11684 0.85344) (xy -0.09144 0.87376) (xy -0.0635 0.889)
						(xy -0.03175 0.89916) (xy 0 0.9017) (xy 0.03175 0.89916) (xy 0.0635 0.889) (xy 0.09144 0.87376)
						(xy 0.11684 0.85344) (xy 0.13716 0.82804) (xy 0.1524 0.8001) (xy 0.16256 0.76835) (xy 0.1651 0.7366)
						(xy 0.1651 0.11938) (xy 0.17272 0.11176) (xy 0.19812 0.0762) (xy 0.2032 0.06604) (xy 0.20701 0.05715)
						(xy 0.21209 0.04699) (xy 0.2159 0.03683) (xy 0.21844 0.02667) (xy 0.22225 0.01524) (xy 0.22352 0.00508)
						(xy 0.22606 -0.00508) (xy 0.22733 -0.01651) (xy 0.22733 -0.02667) (xy 0.2286 -0.0381) (xy 0.22733 -0.04953)
						(xy 0.22733 -0.05969) (xy 0.22606 -0.07112) (xy 0.22352 -0.08128) (xy 0.22225 -0.09144) (xy 0.21844 -0.10287)
						(xy 0.2159 -0.11303) (xy 0.21209 -0.12319) (xy 0.20701 -0.13335) (xy 0.2032 -0.14224) (xy 0.19812 -0.1524)
						(xy 0.17272 -0.18796) (xy 0.1651 -0.19558) (xy 0.1651 -0.7366) (xy 0.16256 -0.76835) (xy 0.1524 -0.8001)
						(xy 0.13716 -0.82804) (xy 0.11684 -0.85344) (xy 0.09144 -0.87376) (xy 0.0635 -0.889) (xy 0.03175 -0.89916)
					)
					(width 0)
					(fill yes)
				)
			)
		)
		(pad "128" smd custom
			(at 8.850122 4.100068 180)
			(size 0.1143 0.1143)
			(layers "B.Cu" "B.Mask" "B.Paste")
			(net "M_B_ODT1")
			(options
				(clearance outline)
				(anchor circle)
			)
			(primitives
				(gr_poly
					(pts
						(xy 0 -0.9017) (xy -0.03175 -0.89916) (xy -0.0635 -0.889) (xy -0.09144 -0.87376) (xy -0.11684 -0.85344)
						(xy -0.13716 -0.82804) (xy -0.1524 -0.8001) (xy -0.16256 -0.76835) (xy -0.1651 -0.7366) (xy -0.1651 -0.11938)
						(xy -0.17272 -0.11176) (xy -0.19812 -0.0762) (xy -0.2032 -0.06604) (xy -0.20701 -0.05715) (xy -0.21209 -0.04699)
						(xy -0.2159 -0.03683) (xy -0.21844 -0.02667) (xy -0.22225 -0.01524) (xy -0.22352 -0.00508) (xy -0.22606 0.00508)
						(xy -0.22733 0.01651) (xy -0.22733 0.02667) (xy -0.2286 0.0381) (xy -0.22733 0.04953) (xy -0.22733 0.05969)
						(xy -0.22606 0.07112) (xy -0.22352 0.08128) (xy -0.22225 0.09144) (xy -0.21844 0.10287) (xy -0.2159 0.11303)
						(xy -0.21209 0.12319) (xy -0.20701 0.13335) (xy -0.2032 0.14224) (xy -0.19812 0.1524) (xy -0.17272 0.18796)
						(xy -0.1651 0.19558) (xy -0.1651 0.7366) (xy -0.16256 0.76835) (xy -0.1524 0.8001) (xy -0.13716 0.82804)
						(xy -0.11684 0.85344) (xy -0.09144 0.87376) (xy -0.0635 0.889) (xy -0.03175 0.89916) (xy 0 0.9017)
						(xy 0.03175 0.89916) (xy 0.0635 0.889) (xy 0.09144 0.87376) (xy 0.11684 0.85344) (xy 0.13716 0.82804)
						(xy 0.1524 0.8001) (xy 0.16256 0.76835) (xy 0.1651 0.7366) (xy 0.1651 0.19685) (xy 0.17272 0.18923)
						(xy 0.17907 0.18034) (xy 0.18669 0.17145) (xy 0.19177 0.16256) (xy 0.19812 0.15367) (xy 0.20828 0.13335)
						(xy 0.21971 0.10287) (xy 0.22225 0.09271) (xy 0.22479 0.08128) (xy 0.22606 0.07112) (xy 0.2286 0.05969)
						(xy 0.2286 0.01651) (xy 0.22606 0.00508) (xy 0.22479 -0.00508) (xy 0.22225 -0.01651) (xy 0.21971 -0.02667)
						(xy 0.20828 -0.05715) (xy 0.19812 -0.07747) (xy 0.19177 -0.08636) (xy 0.18669 -0.09525) (xy 0.17907 -0.10414)
						(xy 0.17272 -0.11303) (xy 0.1651 -0.12065) (xy 0.1651 -0.7366) (xy 0.16256 -0.76835) (xy 0.1524 -0.8001)
						(xy 0.13716 -0.82804) (xy 0.11684 -0.85344) (xy 0.09144 -0.87376) (xy 0.0635 -0.889) (xy 0.03175 -0.89916)
					)
					(width 0)
					(fill yes)
				)
			)
		)
		(pad "129" smd custom
			(at 9.150096 -4.100068 180)
			(size 0.1143 0.1143)
			(layers "B.Cu" "B.Mask" "B.Paste")
			(net "M_B_CS_N1")
			(options
				(clearance outline)
				(anchor circle)
			)
			(primitives
				(gr_poly
					(pts
						(xy 0 -0.9017) (xy -0.03175 -0.89916) (xy -0.0635 -0.889) (xy -0.09144 -0.87376) (xy -0.11684 -0.85344)
						(xy -0.13716 -0.82804) (xy -0.1524 -0.8001) (xy -0.16256 -0.76835) (xy -0.1651 -0.7366) (xy -0.1651 -0.44958)
						(xy -0.17272 -0.44196) (xy -0.19812 -0.4064) (xy -0.2032 -0.39624) (xy -0.20701 -0.38735) (xy -0.21209 -0.37719)
						(xy -0.2159 -0.36703) (xy -0.21844 -0.35687) (xy -0.22225 -0.34544) (xy -0.22352 -0.33528) (xy -0.22606 -0.32512)
						(xy -0.22733 -0.31369) (xy -0.22733 -0.30353) (xy -0.2286 -0.2921) (xy -0.22733 -0.28067) (xy -0.22733 -0.27051)
						(xy -0.22606 -0.25908) (xy -0.22352 -0.24892) (xy -0.22225 -0.23876) (xy -0.21844 -0.22733) (xy -0.2159 -0.21717)
						(xy -0.21209 -0.20701) (xy -0.20701 -0.19685) (xy -0.2032 -0.18796) (xy -0.19812 -0.1778) (xy -0.17272 -0.14224)
						(xy -0.1651 -0.13462) (xy -0.1651 0.7366) (xy -0.16256 0.76835) (xy -0.1524 0.8001) (xy -0.13716 0.82804)
						(xy -0.11684 0.85344) (xy -0.09144 0.87376) (xy -0.0635 0.889) (xy -0.03175 0.89916) (xy 0 0.9017)
						(xy 0.03175 0.89916) (xy 0.0635 0.889) (xy 0.09144 0.87376) (xy 0.11684 0.85344) (xy 0.13716 0.82804)
						(xy 0.1524 0.8001) (xy 0.16256 0.76835) (xy 0.1651 0.7366) (xy 0.1651 -0.13462) (xy 0.17272 -0.14224)
						(xy 0.19812 -0.1778) (xy 0.2032 -0.18796) (xy 0.20701 -0.19685) (xy 0.21209 -0.20701) (xy 0.2159 -0.21717)
						(xy 0.21844 -0.22733) (xy 0.22225 -0.23876) (xy 0.22352 -0.24892) (xy 0.22606 -0.25908) (xy 0.22733 -0.27051)
						(xy 0.22733 -0.28067) (xy 0.2286 -0.2921) (xy 0.22733 -0.30353) (xy 0.22733 -0.31369) (xy 0.22606 -0.32512)
						(xy 0.22352 -0.33528) (xy 0.22225 -0.34544) (xy 0.21844 -0.35687) (xy 0.2159 -0.36703) (xy 0.21209 -0.37719)
						(xy 0.20701 -0.38735) (xy 0.2032 -0.39624) (xy 0.19812 -0.4064) (xy 0.17272 -0.44196) (xy 0.1651 -0.44958)
						(xy 0.1651 -0.7366) (xy 0.16256 -0.76835) (xy 0.1524 -0.8001) (xy 0.13716 -0.82804) (xy 0.11684 -0.85344)
						(xy 0.09144 -0.87376) (xy 0.0635 -0.889) (xy 0.03175 -0.89916)
					)
					(width 0)
					(fill yes)
				)
			)
		)
		(pad "130" smd custom
			(at 9.45007 4.100068 180)
			(size 0.1143 0.1143)
			(layers "B.Cu" "B.Mask" "B.Paste")
			(net "M_B_MA13")
			(options
				(clearance outline)
				(anchor circle)
			)
			(primitives
				(gr_poly
					(pts
						(xy 0 -0.9017) (xy -0.03175 -0.89916) (xy -0.0635 -0.889) (xy -0.09144 -0.87376) (xy -0.11684 -0.85344)
						(xy -0.13716 -0.82804) (xy -0.1524 -0.8001) (xy -0.16256 -0.76835) (xy -0.1651 -0.7366) (xy -0.1651 0.13462)
						(xy -0.17272 0.14224) (xy -0.19812 0.1778) (xy -0.2032 0.18796) (xy -0.20701 0.19685) (xy -0.21209 0.20701)
						(xy -0.2159 0.21717) (xy -0.21844 0.22733) (xy -0.22225 0.23876) (xy -0.22352 0.24892) (xy -0.22606 0.25908)
						(xy -0.22733 0.27051) (xy -0.22733 0.28067) (xy -0.2286 0.2921) (xy -0.22733 0.30353) (xy -0.22733 0.31369)
						(xy -0.22606 0.32512) (xy -0.22352 0.33528) (xy -0.22225 0.34544) (xy -0.21844 0.35687) (xy -0.2159 0.36703)
						(xy -0.21209 0.37719) (xy -0.20701 0.38735) (xy -0.2032 0.39624) (xy -0.19812 0.4064) (xy -0.17272 0.44196)
						(xy -0.1651 0.44958) (xy -0.1651 0.7366) (xy -0.16256 0.76835) (xy -0.1524 0.8001) (xy -0.13716 0.82804)
						(xy -0.11684 0.85344) (xy -0.09144 0.87376) (xy -0.0635 0.889) (xy -0.03175 0.89916) (xy 0 0.9017)
						(xy 0.03175 0.89916) (xy 0.0635 0.889) (xy 0.09144 0.87376) (xy 0.11684 0.85344) (xy 0.13716 0.82804)
						(xy 0.1524 0.8001) (xy 0.16256 0.76835) (xy 0.1651 0.7366) (xy 0.1651 0.44958) (xy 0.17272 0.44196)
						(xy 0.19812 0.4064) (xy 0.2032 0.39624) (xy 0.20701 0.38735) (xy 0.21209 0.37719) (xy 0.2159 0.36703)
						(xy 0.21844 0.35687) (xy 0.22225 0.34544) (xy 0.22352 0.33528) (xy 0.22606 0.32512) (xy 0.22733 0.31369)
						(xy 0.22733 0.30353) (xy 0.2286 0.2921) (xy 0.22733 0.28067) (xy 0.22733 0.27051) (xy 0.22606 0.25908)
						(xy 0.22352 0.24892) (xy 0.22225 0.23876) (xy 0.21844 0.22733) (xy 0.2159 0.21717) (xy 0.21209 0.20701)
						(xy 0.20701 0.19685) (xy 0.2032 0.18796) (xy 0.19812 0.1778) (xy 0.17272 0.14224) (xy 0.1651 0.13462)
						(xy 0.1651 -0.7366) (xy 0.16256 -0.76835) (xy 0.1524 -0.8001) (xy 0.13716 -0.82804) (xy 0.11684 -0.85344)
						(xy 0.09144 -0.87376) (xy 0.0635 -0.889) (xy 0.03175 -0.89916)
					)
					(width 0)
					(fill yes)
				)
			)
		)
		(pad "131" smd custom
			(at 9.750044 -4.100068 180)
			(size 0.1143 0.1143)
			(layers "B.Cu" "B.Mask" "B.Paste")
			(net "PV_VDDR")
			(options
				(clearance outline)
				(anchor circle)
			)
			(primitives
				(gr_poly
					(pts
						(xy 0 -0.9017) (xy -0.03175 -0.89916) (xy -0.0635 -0.889) (xy -0.09144 -0.87376) (xy -0.11684 -0.85344)
						(xy -0.13716 -0.82804) (xy -0.1524 -0.8001) (xy -0.16256 -0.76835) (xy -0.1651 -0.7366) (xy -0.1651 -0.19685)
						(xy -0.17272 -0.18923) (xy -0.17907 -0.18034) (xy -0.18669 -0.17145) (xy -0.19177 -0.16256) (xy -0.19812 -0.15367)
						(xy -0.20828 -0.13335) (xy -0.21971 -0.10287) (xy -0.22225 -0.09271) (xy -0.22479 -0.08128) (xy -0.22606 -0.07112)
						(xy -0.2286 -0.05969) (xy -0.2286 -0.01651) (xy -0.22606 -0.00508) (xy -0.22479 0.00508) (xy -0.22225 0.01651)
						(xy -0.21971 0.02667) (xy -0.20828 0.05715) (xy -0.19812 0.07747) (xy -0.19177 0.08636) (xy -0.18669 0.09525)
						(xy -0.17907 0.10414) (xy -0.17272 0.11303) (xy -0.1651 0.12065) (xy -0.1651 0.7366) (xy -0.16256 0.76835)
						(xy -0.1524 0.8001) (xy -0.13716 0.82804) (xy -0.11684 0.85344) (xy -0.09144 0.87376) (xy -0.0635 0.889)
						(xy -0.03175 0.89916) (xy 0 0.9017) (xy 0.03175 0.89916) (xy 0.0635 0.889) (xy 0.09144 0.87376)
						(xy 0.11684 0.85344) (xy 0.13716 0.82804) (xy 0.1524 0.8001) (xy 0.16256 0.76835) (xy 0.1651 0.7366)
						(xy 0.1651 0.11938) (xy 0.17272 0.11176) (xy 0.19812 0.0762) (xy 0.2032 0.06604) (xy 0.20701 0.05715)
						(xy 0.21209 0.04699) (xy 0.2159 0.03683) (xy 0.21844 0.02667) (xy 0.22225 0.01524) (xy 0.22352 0.00508)
						(xy 0.22606 -0.00508) (xy 0.22733 -0.01651) (xy 0.22733 -0.02667) (xy 0.2286 -0.0381) (xy 0.22733 -0.04953)
						(xy 0.22733 -0.05969) (xy 0.22606 -0.07112) (xy 0.22352 -0.08128) (xy 0.22225 -0.09144) (xy 0.21844 -0.10287)
						(xy 0.2159 -0.11303) (xy 0.21209 -0.12319) (xy 0.20701 -0.13335) (xy 0.2032 -0.14224) (xy 0.19812 -0.1524)
						(xy 0.17272 -0.18796) (xy 0.1651 -0.19558) (xy 0.1651 -0.7366) (xy 0.16256 -0.76835) (xy 0.1524 -0.8001)
						(xy 0.13716 -0.82804) (xy 0.11684 -0.85344) (xy 0.09144 -0.87376) (xy 0.0635 -0.889) (xy 0.03175 -0.89916)
					)
					(width 0)
					(fill yes)
				)
			)
		)
		(pad "132" smd custom
			(at 10.050018 4.100068 180)
			(size 0.1143 0.1143)
			(layers "B.Cu" "B.Mask" "B.Paste")
			(net "PV_VDDR")
			(options
				(clearance outline)
				(anchor circle)
			)
			(primitives
				(gr_poly
					(pts
						(xy 0 -0.9017) (xy -0.03175 -0.89916) (xy -0.0635 -0.889) (xy -0.09144 -0.87376) (xy -0.11684 -0.85344)
						(xy -0.13716 -0.82804) (xy -0.1524 -0.8001) (xy -0.16256 -0.76835) (xy -0.1651 -0.7366) (xy -0.1651 -0.11938)
						(xy -0.17272 -0.11176) (xy -0.19812 -0.0762) (xy -0.2032 -0.06604) (xy -0.20701 -0.05715) (xy -0.21209 -0.04699)
						(xy -0.2159 -0.03683) (xy -0.21844 -0.02667) (xy -0.22225 -0.01524) (xy -0.22352 -0.00508) (xy -0.22606 0.00508)
						(xy -0.22733 0.01651) (xy -0.22733 0.02667) (xy -0.2286 0.0381) (xy -0.22733 0.04953) (xy -0.22733 0.05969)
						(xy -0.22606 0.07112) (xy -0.22352 0.08128) (xy -0.22225 0.09144) (xy -0.21844 0.10287) (xy -0.2159 0.11303)
						(xy -0.21209 0.12319) (xy -0.20701 0.13335) (xy -0.2032 0.14224) (xy -0.19812 0.1524) (xy -0.17272 0.18796)
						(xy -0.1651 0.19558) (xy -0.1651 0.7366) (xy -0.16256 0.76835) (xy -0.1524 0.8001) (xy -0.13716 0.82804)
						(xy -0.11684 0.85344) (xy -0.09144 0.87376) (xy -0.0635 0.889) (xy -0.03175 0.89916) (xy 0 0.9017)
						(xy 0.03175 0.89916) (xy 0.0635 0.889) (xy 0.09144 0.87376) (xy 0.11684 0.85344) (xy 0.13716 0.82804)
						(xy 0.1524 0.8001) (xy 0.16256 0.76835) (xy 0.1651 0.7366) (xy 0.1651 0.19685) (xy 0.17272 0.18923)
						(xy 0.17907 0.18034) (xy 0.18669 0.17145) (xy 0.19177 0.16256) (xy 0.19812 0.15367) (xy 0.20828 0.13335)
						(xy 0.21971 0.10287) (xy 0.22225 0.09271) (xy 0.22479 0.08128) (xy 0.22606 0.07112) (xy 0.2286 0.05969)
						(xy 0.2286 0.01651) (xy 0.22606 0.00508) (xy 0.22479 -0.00508) (xy 0.22225 -0.01651) (xy 0.21971 -0.02667)
						(xy 0.20828 -0.05715) (xy 0.19812 -0.07747) (xy 0.19177 -0.08636) (xy 0.18669 -0.09525) (xy 0.17907 -0.10414)
						(xy 0.17272 -0.11303) (xy 0.1651 -0.12065) (xy 0.1651 -0.7366) (xy 0.16256 -0.76835) (xy 0.1524 -0.8001)
						(xy 0.13716 -0.82804) (xy 0.11684 -0.85344) (xy 0.09144 -0.87376) (xy 0.0635 -0.889) (xy 0.03175 -0.89916)
					)
					(width 0)
					(fill yes)
				)
			)
		)
	)
)
